(kicad_pcb
	(version 20260206)
	(generator "pcbnew")
	(generator_version "10.0")
	(general
		(thickness 1.6)
		(legacy_teardrops no)
	)
	(paper "A4")
	(title_block
		(title "v1-chassis-manager — T6M_CM_d_v01_1031_1645.brd")
		(comment 1 "Open CloudServer (Microsoft) / footprints 336-346 of 2512")
	)
	(layers
		(0 "F.Cu" signal "TOP")
		(4 "In1.Cu" signal "GND1")
		(6 "In2.Cu" signal "IN1")
		(8 "In3.Cu" signal "VCC1")
		(10 "In4.Cu" signal "VCC2")
		(12 "In5.Cu" signal "GND2")
		(14 "In6.Cu" signal "IN2")
		(16 "In7.Cu" signal "IN3")
		(18 "In8.Cu" signal "GND3")
		(2 "B.Cu" signal "BOTTOM")
		(9 "F.Adhes" user "F.Adhesive")
		(11 "B.Adhes" user "B.Adhesive")
		(13 "F.Paste" user "Package Geometry/Pastemask Top")
		(15 "B.Paste" user "Package Geometry/Pastemask Bottom")
		(5 "F.SilkS" user "Ref Des/Silkscreen Top")
		(7 "B.SilkS" user "Ref Des/Silkscreen Bottom")
		(1 "F.Mask" user "Board Geometry/Soldermask Top")
		(3 "B.Mask" user "Board Geometry/Soldermask Bottom")
		(17 "Dwgs.User" user "User.Drawings")
		(19 "Cmts.User" user "User.Comments")
		(21 "Eco1.User" user "User.Eco1")
		(23 "Eco2.User" user "User.Eco2")
		(25 "Edge.Cuts" user "Board Geometry/Outline")
		(27 "Margin" user)
		(31 "F.CrtYd" user "Package Geometry/Place Bound Top")
		(29 "B.CrtYd" user "Package Geometry/Place Bound Bottom")
		(35 "F.Fab" user "Ref Des/Assembly Top")
		(33 "B.Fab" user "Ref Des/Assembly Bottom")
	)
	(footprint ""
		(layer "F.Cu")
		(at 9.550146 -11.613896 90)
		(property "Reference" "C181"
			(at -0.984758 -4.7117 90)
			(unlocked yes)
			(layer "F.SilkS")
			(effects
				(font
					(size 0.7874 0.5842)
					(thickness 0.1524)
				)
				(justify left)
			)
		)
		(property "Value" ""
			(at 0 0 90)
			(layer "F.Fab")
			(effects
				(font
					(size 1.27 1.27)
				)
			)
		)
		(duplicate_pad_numbers_are_jumpers no)
		(fp_line
			(start 0.7874 -0.4064)
			(end 0.7874 0.4064)
			(stroke
				(width 0.1524)
				(type default)
			)
			(layer "F.SilkS")
		)
		(fp_line
			(start -0.7874 -0.4064)
			(end 0.7874 -0.4064)
			(stroke
				(width 0.1524)
				(type default)
			)
			(layer "F.SilkS")
		)
		(fp_line
			(start 0 0.381)
			(end 0 -0.381)
			(stroke
				(width 0.1524)
				(type default)
			)
			(layer "F.SilkS")
		)
		(fp_line
			(start 0.7874 0.4064)
			(end -0.7874 0.4064)
			(stroke
				(width 0.1524)
				(type default)
			)
			(layer "F.SilkS")
		)
		(fp_line
			(start -0.7874 0.4064)
			(end -0.7874 -0.4064)
			(stroke
				(width 0.1524)
				(type default)
			)
			(layer "F.SilkS")
		)
		(fp_poly
			(pts
				(xy -0.5334 0.254) (xy -0.635 0.254) (xy -0.635 0.2286) (xy -0.635 -0.254) (xy -0.5334 -0.254) (xy -0.5334 -0.2794)
				(xy 0.5334 -0.2794) (xy 0.5334 -0.254) (xy 0.635 -0.254) (xy 0.635 0.254) (xy 0.5334 0.254) (xy 0.5334 0.2794)
				(xy -0.508 0.2794) (xy -0.5334 0.2794)
			)
			(stroke
				(width 0)
				(type default)
			)
			(fill no)
			(layer "F.CrtYd")
		)
		(pad "1" smd rect
			(at 0.40005 0 90)
			(size 0.4572 0.508)
			(layers "F.Cu" "F.Mask" "F.Paste")
			(net "PV_VDDR_NODE1_VREF_LM321")
		)
		(pad "2" smd rect
			(at -0.40005 0 90)
			(size 0.4572 0.508)
			(layers "F.Cu" "F.Mask" "F.Paste")
			(net "GND")
		)
	)
	(footprint ""
		(layer "F.Cu")
		(at 58.753756 -14.910054 -90)
		(property "Reference" "PC84"
			(at 0.031242 6.692646 90)
			(unlocked yes)
			(layer "F.SilkS")
			(effects
				(font
					(size 0.7874 0.5842)
					(thickness 0.1524)
				)
				(justify left)
			)
		)
		(property "Value" ""
			(at 0 0 270)
			(layer "F.Fab")
			(effects
				(font
					(size 1.27 1.27)
				)
			)
		)
		(duplicate_pad_numbers_are_jumpers no)
		(fp_line
			(start -1.905 0.8636)
			(end -1.905 -0.8636)
			(stroke
				(width 0.1524)
				(type default)
			)
			(layer "F.SilkS")
		)
		(fp_line
			(start 1.905 0.8636)
			(end -1.905 0.8636)
			(stroke
				(width 0.1524)
				(type default)
			)
			(layer "F.SilkS")
		)
		(fp_line
			(start 0 0.8382)
			(end 0 -0.8382)
			(stroke
				(width 0.1524)
				(type default)
			)
			(layer "F.SilkS")
		)
		(fp_line
			(start -1.905 -0.8636)
			(end 1.905 -0.8636)
			(stroke
				(width 0.1524)
				(type default)
			)
			(layer "F.SilkS")
		)
		(fp_line
			(start 1.905 -0.8636)
			(end 1.905 0.8636)
			(stroke
				(width 0.1524)
				(type default)
			)
			(layer "F.SilkS")
		)
		(fp_rect
			(start -1.524 0.7366)
			(end 1.524 -0.7366)
			(stroke
				(width 0)
				(type default)
			)
			(fill no)
			(layer "F.CrtYd")
		)
		(pad "1" smd rect
			(at 0.94996 0 270)
			(size 1.1176 1.3716)
			(layers "F.Cu" "F.Mask" "F.Paste")
			(net "PV_VDDR_NODE1")
		)
		(pad "2" smd rect
			(at -0.94996 0 270)
			(size 1.1176 1.3716)
			(layers "F.Cu" "F.Mask" "F.Paste")
			(net "GND")
		)
	)
	(footprint ""
		(layer "F.Cu")
		(at 72.24776 -185.205624 -90)
		(property "Reference" "R947"
			(at -4.006088 1.07188 90)
			(unlocked yes)
			(layer "F.SilkS")
			(effects
				(font
					(size 0.7874 0.5842)
					(thickness 0.1524)
				)
				(justify left)
			)
		)
		(property "Value" ""
			(at 0 0 270)
			(layer "F.Fab")
			(effects
				(font
					(size 1.27 1.27)
				)
			)
		)
		(duplicate_pad_numbers_are_jumpers no)
		(fp_line
			(start -0.7874 0.4064)
			(end -0.7874 -0.4064)
			(stroke
				(width 0.1524)
				(type default)
			)
			(layer "F.SilkS")
		)
		(fp_line
			(start 0.7874 0.4064)
			(end -0.7874 0.4064)
			(stroke
				(width 0.1524)
				(type default)
			)
			(layer "F.SilkS")
		)
		(fp_line
			(start -0.7874 -0.4064)
			(end 0.7874 -0.4064)
			(stroke
				(width 0.1524)
				(type default)
			)
			(layer "F.SilkS")
		)
		(fp_line
			(start 0.7874 -0.4064)
			(end 0.7874 0.4064)
			(stroke
				(width 0.1524)
				(type default)
			)
			(layer "F.SilkS")
		)
		(fp_poly
			(pts
				(xy -0.508 0.2794) (xy -0.508 0.2286) (xy -0.635 0.2286) (xy -0.635 -0.254) (xy -0.5334 -0.254)
				(xy -0.5334 -0.2794) (xy 0.5334 -0.2794) (xy 0.5334 -0.254) (xy 0.635 -0.254) (xy 0.635 0.254) (xy 0.5334 0.254)
				(xy 0.5334 0.2794)
			)
			(stroke
				(width 0)
				(type default)
			)
			(fill no)
			(layer "F.CrtYd")
		)
		(pad "1" smd rect
			(at 0.40005 0 270)
			(size 0.4572 0.508)
			(layers "F.Cu" "F.Mask" "F.Paste")
			(net "UART_T4_NODE3_TXD")
		)
		(pad "2" smd rect
			(at -0.40005 0 270)
			(size 0.4572 0.508)
			(layers "F.Cu" "F.Mask" "F.Paste")
			(net "UART_T4_NODE3_TXD_R")
		)
	)
	(footprint ""
		(layer "F.Cu")
		(at 35.243008 -188.652404)
		(property "Reference" "C769"
			(at -1.53162 -5.211064 0)
			(unlocked yes)
			(layer "F.SilkS")
			(effects
				(font
					(size 0.7874 0.5842)
					(thickness 0.1524)
				)
				(justify left)
			)
		)
		(property "Value" ""
			(at 0 0 0)
			(layer "F.Fab")
			(effects
				(font
					(size 1.27 1.27)
				)
			)
		)
		(duplicate_pad_numbers_are_jumpers no)
		(fp_line
			(start -0.7874 -0.4064)
			(end 0.7874 -0.4064)
			(stroke
				(width 0.1524)
				(type default)
			)
			(layer "F.SilkS")
		)
		(fp_line
			(start -0.7874 0.4064)
			(end -0.7874 -0.4064)
			(stroke
				(width 0.1524)
				(type default)
			)
			(layer "F.SilkS")
		)
		(fp_line
			(start 0 0.381)
			(end 0 -0.381)
			(stroke
				(width 0.1524)
				(type default)
			)
			(layer "F.SilkS")
		)
		(fp_line
			(start 0.7874 -0.4064)
			(end 0.7874 0.4064)
			(stroke
				(width 0.1524)
				(type default)
			)
			(layer "F.SilkS")
		)
		(fp_line
			(start 0.7874 0.4064)
			(end -0.7874 0.4064)
			(stroke
				(width 0.1524)
				(type default)
			)
			(layer "F.SilkS")
		)
		(fp_poly
			(pts
				(xy -0.5334 0.254) (xy -0.635 0.254) (xy -0.635 0.2286) (xy -0.635 -0.254) (xy -0.5334 -0.254) (xy -0.5334 -0.2794)
				(xy 0.5334 -0.2794) (xy 0.5334 -0.254) (xy 0.635 -0.254) (xy 0.635 0.254) (xy 0.5334 0.254) (xy 0.5334 0.2794)
				(xy -0.508 0.2794) (xy -0.5334 0.2794)
			)
			(stroke
				(width 0)
				(type default)
			)
			(fill no)
			(layer "F.CrtYd")
		)
		(pad "1" smd rect
			(at 0.40005 0)
			(size 0.4572 0.508)
			(layers "F.Cu" "F.Mask" "F.Paste")
			(net "P12V_PDB")
		)
		(pad "2" smd rect
			(at -0.40005 0)
			(size 0.4572 0.508)
			(layers "F.Cu" "F.Mask" "F.Paste")
			(net "GND")
		)
	)
	(footprint ""
		(layer "F.Cu")
		(at 117.023388 -135.617204 90)
		(property "Reference" "PR69"
			(at 2.566416 5.091938 90)
			(unlocked yes)
			(layer "F.SilkS")
			(effects
				(font
					(size 0.635 0.4064)
					(thickness 0.1524)
				)
				(justify left)
			)
		)
		(property "Value" ""
			(at 0 0 90)
			(layer "F.Fab")
			(effects
				(font
					(size 1.27 1.27)
				)
			)
		)
		(duplicate_pad_numbers_are_jumpers no)
		(fp_line
			(start 0.7874 -0.4064)
			(end 0.7874 0.4064)
			(stroke
				(width 0.1524)
				(type default)
			)
			(layer "F.SilkS")
		)
		(fp_line
			(start -0.7874 -0.4064)
			(end 0.7874 -0.4064)
			(stroke
				(width 0.1524)
				(type default)
			)
			(layer "F.SilkS")
		)
		(fp_line
			(start 0.7874 0.4064)
			(end -0.7874 0.4064)
			(stroke
				(width 0.1524)
				(type default)
			)
			(layer "F.SilkS")
		)
		(fp_line
			(start -0.7874 0.4064)
			(end -0.7874 -0.4064)
			(stroke
				(width 0.1524)
				(type default)
			)
			(layer "F.SilkS")
		)
		(fp_poly
			(pts
				(xy -0.508 0.2794) (xy -0.508 0.2286) (xy -0.635 0.2286) (xy -0.635 -0.254) (xy -0.5334 -0.254)
				(xy -0.5334 -0.2794) (xy 0.5334 -0.2794) (xy 0.5334 -0.254) (xy 0.635 -0.254) (xy 0.635 0.254) (xy 0.5334 0.254)
				(xy 0.5334 0.2794)
			)
			(stroke
				(width 0)
				(type default)
			)
			(fill no)
			(layer "F.CrtYd")
		)
		(pad "1" smd rect
			(at 0.40005 0 90)
			(size 0.4572 0.508)
			(layers "F.Cu" "F.Mask" "F.Paste")
			(net "VR_PVCCP_NODE1_FB")
		)
		(pad "2" smd rect
			(at -0.40005 0 90)
			(size 0.4572 0.508)
			(layers "F.Cu" "F.Mask" "F.Paste")
			(net "VR_PVCCP_NODE1_FB_RR")
		)
	)
	(footprint ""
		(layer "F.Cu")
		(at 94.451932 -164.123624)
		(property "Reference" "R770"
			(at 86.632288 73.221596 0)
			(unlocked yes)
			(layer "F.SilkS")
			(effects
				(font
					(size 0.7874 0.5842)
					(thickness 0.1524)
				)
				(justify left)
			)
		)
		(property "Value" ""
			(at 0 0 0)
			(layer "F.Fab")
			(effects
				(font
					(size 1.27 1.27)
				)
			)
		)
		(duplicate_pad_numbers_are_jumpers no)
		(fp_line
			(start -0.7874 -0.4064)
			(end 0.7874 -0.4064)
			(stroke
				(width 0.1524)
				(type default)
			)
			(layer "F.SilkS")
		)
		(fp_line
			(start -0.7874 0.4064)
			(end -0.7874 -0.4064)
			(stroke
				(width 0.1524)
				(type default)
			)
			(layer "F.SilkS")
		)
		(fp_line
			(start 0.7874 -0.4064)
			(end 0.7874 0.4064)
			(stroke
				(width 0.1524)
				(type default)
			)
			(layer "F.SilkS")
		)
		(fp_line
			(start 0.7874 0.4064)
			(end -0.7874 0.4064)
			(stroke
				(width 0.1524)
				(type default)
			)
			(layer "F.SilkS")
		)
		(fp_poly
			(pts
				(xy -0.508 0.2794) (xy -0.508 0.2286) (xy -0.635 0.2286) (xy -0.635 -0.254) (xy -0.5334 -0.254)
				(xy -0.5334 -0.2794) (xy 0.5334 -0.2794) (xy 0.5334 -0.254) (xy 0.635 -0.254) (xy 0.635 0.254) (xy 0.5334 0.254)
				(xy 0.5334 0.2794)
			)
			(stroke
				(width 0)
				(type default)
			)
			(fill no)
			(layer "F.CrtYd")
		)
		(pad "1" smd rect
			(at 0.40005 0)
			(size 0.4572 0.508)
			(layers "F.Cu" "F.Mask" "F.Paste")
			(net "FAN6_TACH_IN")
		)
		(pad "2" smd rect
			(at -0.40005 0)
			(size 0.4572 0.508)
			(layers "F.Cu" "F.Mask" "F.Paste")
			(net "FAN6_TACH")
		)
	)
	(footprint ""
		(layer "F.Cu")
		(at 20.15744 -10.541254 -90)
		(property "Reference" "R808"
			(at 1.17094 -1.56591 90)
			(unlocked yes)
			(layer "F.SilkS")
			(effects
				(font
					(size 0.7874 0.5842)
					(thickness 0.1524)
				)
				(justify left)
			)
		)
		(property "Value" ""
			(at 0 0 270)
			(layer "F.Fab")
			(effects
				(font
					(size 1.27 1.27)
				)
			)
		)
		(duplicate_pad_numbers_are_jumpers no)
		(fp_line
			(start -0.7874 0.4064)
			(end -0.7874 -0.4064)
			(stroke
				(width 0.1524)
				(type default)
			)
			(layer "F.SilkS")
		)
		(fp_line
			(start 0.7874 0.4064)
			(end -0.7874 0.4064)
			(stroke
				(width 0.1524)
				(type default)
			)
			(layer "F.SilkS")
		)
		(fp_line
			(start -0.7874 -0.4064)
			(end 0.7874 -0.4064)
			(stroke
				(width 0.1524)
				(type default)
			)
			(layer "F.SilkS")
		)
		(fp_line
			(start 0.7874 -0.4064)
			(end 0.7874 0.4064)
			(stroke
				(width 0.1524)
				(type default)
			)
			(layer "F.SilkS")
		)
		(fp_poly
			(pts
				(xy -0.508 0.2794) (xy -0.508 0.2286) (xy -0.635 0.2286) (xy -0.635 -0.254) (xy -0.5334 -0.254)
				(xy -0.5334 -0.2794) (xy 0.5334 -0.2794) (xy 0.5334 -0.254) (xy 0.635 -0.254) (xy 0.635 0.254) (xy 0.5334 0.254)
				(xy 0.5334 0.2794)
			)
			(stroke
				(width 0)
				(type default)
			)
			(fill no)
			(layer "F.CrtYd")
		)
		(pad "1" smd rect
			(at 0.40005 0 270)
			(size 0.4572 0.508)
			(layers "F.Cu" "F.Mask" "F.Paste")
			(net "N53608934")
		)
		(pad "2" smd rect
			(at -0.40005 0 270)
			(size 0.4572 0.508)
			(layers "F.Cu" "F.Mask" "F.Paste")
			(net "GND")
		)
	)
	(footprint ""
		(layer "F.Cu")
		(at 48.24476 -185.205624 90)
		(property "Reference" "R842"
			(at 4.006088 0.055372 90)
			(unlocked yes)
			(layer "F.SilkS")
			(effects
				(font
					(size 0.7874 0.5842)
					(thickness 0.1524)
				)
				(justify left)
			)
		)
		(property "Value" ""
			(at 0 0 90)
			(layer "F.Fab")
			(effects
				(font
					(size 1.27 1.27)
				)
			)
		)
		(duplicate_pad_numbers_are_jumpers no)
		(fp_line
			(start 0.7874 -0.4064)
			(end 0.7874 0.4064)
			(stroke
				(width 0.1524)
				(type default)
			)
			(layer "F.SilkS")
		)
		(fp_line
			(start -0.7874 -0.4064)
			(end 0.7874 -0.4064)
			(stroke
				(width 0.1524)
				(type default)
			)
			(layer "F.SilkS")
		)
		(fp_line
			(start 0.7874 0.4064)
			(end -0.7874 0.4064)
			(stroke
				(width 0.1524)
				(type default)
			)
			(layer "F.SilkS")
		)
		(fp_line
			(start -0.7874 0.4064)
			(end -0.7874 -0.4064)
			(stroke
				(width 0.1524)
				(type default)
			)
			(layer "F.SilkS")
		)
		(fp_poly
			(pts
				(xy -0.508 0.2794) (xy -0.508 0.2286) (xy -0.635 0.2286) (xy -0.635 -0.254) (xy -0.5334 -0.254)
				(xy -0.5334 -0.2794) (xy 0.5334 -0.2794) (xy 0.5334 -0.254) (xy 0.635 -0.254) (xy 0.635 0.254) (xy 0.5334 0.254)
				(xy 0.5334 0.2794)
			)
			(stroke
				(width 0)
				(type default)
			)
			(fill no)
			(layer "F.CrtYd")
		)
		(pad "1" smd rect
			(at 0.40005 0 90)
			(size 0.4572 0.508)
			(layers "F.Cu" "F.Mask" "F.Paste")
			(net "PSU5_AC_OK_R")
		)
		(pad "2" smd rect
			(at -0.40005 0 90)
			(size 0.4572 0.508)
			(layers "F.Cu" "F.Mask" "F.Paste")
			(net "PSU5_AC_OK")
		)
	)
	(footprint ""
		(layer "F.Cu")
		(at 80.91297 -96.665034 180)
		(property "Reference" "R1102"
			(at 0.336804 -3.213354 90)
			(unlocked yes)
			(layer "F.SilkS")
			(effects
				(font
					(size 0.635 0.4064)
					(thickness 0.1524)
				)
				(justify left)
			)
		)
		(property "Value" ""
			(at 0 0 180)
			(layer "F.Fab")
			(effects
				(font
					(size 1.27 1.27)
				)
			)
		)
		(duplicate_pad_numbers_are_jumpers no)
		(fp_line
			(start 0.7874 0.4064)
			(end -0.7874 0.4064)
			(stroke
				(width 0.1524)
				(type default)
			)
			(layer "F.SilkS")
		)
		(fp_line
			(start 0.7874 -0.4064)
			(end 0.7874 0.4064)
			(stroke
				(width 0.1524)
				(type default)
			)
			(layer "F.SilkS")
		)
		(fp_line
			(start -0.7874 0.4064)
			(end -0.7874 -0.4064)
			(stroke
				(width 0.1524)
				(type default)
			)
			(layer "F.SilkS")
		)
		(fp_line
			(start -0.7874 -0.4064)
			(end 0.7874 -0.4064)
			(stroke
				(width 0.1524)
				(type default)
			)
			(layer "F.SilkS")
		)
		(fp_poly
			(pts
				(xy -0.508 0.2794) (xy -0.508 0.2286) (xy -0.635 0.2286) (xy -0.635 -0.254) (xy -0.5334 -0.254)
				(xy -0.5334 -0.2794) (xy 0.5334 -0.2794) (xy 0.5334 -0.254) (xy 0.635 -0.254) (xy 0.635 0.254) (xy 0.5334 0.254)
				(xy 0.5334 0.2794)
			)
			(stroke
				(width 0)
				(type default)
			)
			(fill no)
			(layer "F.CrtYd")
		)
		(pad "1" smd rect
			(at 0.40005 0 180)
			(size 0.4572 0.508)
			(layers "F.Cu" "F.Mask" "F.Paste")
			(net "GND")
		)
		(pad "2" smd rect
			(at -0.40005 0 180)
			(size 0.4572 0.508)
			(layers "F.Cu" "F.Mask" "F.Paste")
			(net "P3V3_SUS_NODE1")
		)
	)
	(footprint ""
		(layer "F.Cu")
		(at 107.17276 -185.205624 90)
		(property "Reference" "C696"
			(at 4.768088 0.857758 90)
			(unlocked yes)
			(layer "F.SilkS")
			(effects
				(font
					(size 0.7874 0.5842)
					(thickness 0.1524)
				)
				(justify left)
			)
		)
		(property "Value" ""
			(at 0 0 90)
			(layer "F.Fab")
			(effects
				(font
					(size 1.27 1.27)
				)
			)
		)
		(duplicate_pad_numbers_are_jumpers no)
		(fp_line
			(start 0.7874 -0.4064)
			(end 0.7874 0.4064)
			(stroke
				(width 0.1524)
				(type default)
			)
			(layer "F.SilkS")
		)
		(fp_line
			(start -0.7874 -0.4064)
			(end 0.7874 -0.4064)
			(stroke
				(width 0.1524)
				(type default)
			)
			(layer "F.SilkS")
		)
		(fp_line
			(start 0 0.381)
			(end 0 -0.381)
			(stroke
				(width 0.1524)
				(type default)
			)
			(layer "F.SilkS")
		)
		(fp_line
			(start 0.7874 0.4064)
			(end -0.7874 0.4064)
			(stroke
				(width 0.1524)
				(type default)
			)
			(layer "F.SilkS")
		)
		(fp_line
			(start -0.7874 0.4064)
			(end -0.7874 -0.4064)
			(stroke
				(width 0.1524)
				(type default)
			)
			(layer "F.SilkS")
		)
		(fp_poly
			(pts
				(xy -0.5334 0.254) (xy -0.635 0.254) (xy -0.635 0.2286) (xy -0.635 -0.254) (xy -0.5334 -0.254) (xy -0.5334 -0.2794)
				(xy 0.5334 -0.2794) (xy 0.5334 -0.254) (xy 0.635 -0.254) (xy 0.635 0.254) (xy 0.5334 0.254) (xy 0.5334 0.2794)
				(xy -0.508 0.2794) (xy -0.5334 0.2794)
			)
			(stroke
				(width 0)
				(type default)
			)
			(fill no)
			(layer "F.CrtYd")
		)
		(pad "1" smd rect
			(at 0.40005 0 90)
			(size 0.4572 0.508)
			(layers "F.Cu" "F.Mask" "F.Paste")
			(net "UART_T6_NODE1_RXD")
		)
		(pad "2" smd rect
			(at -0.40005 0 90)
			(size 0.4572 0.508)
			(layers "F.Cu" "F.Mask" "F.Paste")
			(net "GND")
		)
	)
	(footprint ""
		(layer "F.Cu")
		(at 160.81502 -188.08192 90)
		(property "Reference" "R1223"
			(at 1.106932 0.545338 90)
			(unlocked yes)
			(layer "F.SilkS")
			(effects
				(font
					(size 0.7874 0.5842)
					(thickness 0.1524)
				)
				(justify left)
			)
		)
		(property "Value" ""
			(at 0 0 90)
			(layer "F.Fab")
			(effects
				(font
					(size 1.27 1.27)
				)
			)
		)
		(duplicate_pad_numbers_are_jumpers no)
		(fp_line
			(start 0.7874 -0.4064)
			(end 0.7874 0.4064)
			(stroke
				(width 0.1524)
				(type default)
			)
			(layer "F.SilkS")
		)
		(fp_line
			(start -0.7874 -0.4064)
			(end 0.7874 -0.4064)
			(stroke
				(width 0.1524)
				(type default)
			)
			(layer "F.SilkS")
		)
		(fp_line
			(start 0.7874 0.4064)
			(end -0.7874 0.4064)
			(stroke
				(width 0.1524)
				(type default)
			)
			(layer "F.SilkS")
		)
		(fp_line
			(start -0.7874 0.4064)
			(end -0.7874 -0.4064)
			(stroke
				(width 0.1524)
				(type default)
			)
			(layer "F.SilkS")
		)
		(fp_poly
			(pts
				(xy -0.508 0.2794) (xy -0.508 0.2286) (xy -0.635 0.2286) (xy -0.635 -0.254) (xy -0.5334 -0.254)
				(xy -0.5334 -0.2794) (xy 0.5334 -0.2794) (xy 0.5334 -0.254) (xy 0.635 -0.254) (xy 0.635 0.254) (xy 0.5334 0.254)
				(xy 0.5334 0.2794)
			)
			(stroke
				(width 0)
				(type default)
			)
			(fill no)
			(layer "F.CrtYd")
		)
		(pad "1" smd rect
			(at 0.40005 0 90)
			(size 0.4572 0.508)
			(layers "F.Cu" "F.Mask" "F.Paste")
			(net "FAN5_TACH_R")
		)
		(pad "2" smd rect
			(at -0.40005 0 90)
			(size 0.4572 0.508)
			(layers "F.Cu" "F.Mask" "F.Paste")
			(net "GND")
		)
	)
)
